(kicad_pcb
	(version 20260206)
	(generator "pcbnew")
	(generator_version "10.0")
	(general
		(thickness 1.6)
		(legacy_teardrops no)
	)
	(paper "A4")
	(title_block
		(title "03242023_DA0F0TMBIJ0_F0T_Motherboard_J_brd_V01_OCP.brd")
		(comment 1 "Grand Teton / footprints 1768-1773 of 6105")
	)
	(layers
		(0 "F.Cu" signal "TOP")
		(4 "In1.Cu" signal "GND")
		(6 "In2.Cu" signal "IN1")
		(8 "In3.Cu" signal "GND1")
		(10 "In4.Cu" signal "IN2")
		(12 "In5.Cu" signal "GND2")
		(14 "In6.Cu" signal "IN3")
		(16 "In7.Cu" signal "GND3")
		(18 "In8.Cu" signal "VCC")
		(20 "In9.Cu" signal "VCC1")
		(22 "In10.Cu" signal "GND4")
		(24 "In11.Cu" signal "IN4")
		(26 "In12.Cu" signal "GND5")
		(28 "In13.Cu" signal "IN5")
		(30 "In14.Cu" signal "GND6")
		(32 "In15.Cu" signal "IN6")
		(34 "In16.Cu" signal "GND7")
		(2 "B.Cu" signal "BOTTOM")
		(9 "F.Adhes" user "F.Adhesive")
		(11 "B.Adhes" user "B.Adhesive")
		(13 "F.Paste" user "Package Geometry/Pastemask Top")
		(15 "B.Paste" user "Package Geometry/Pastemask Bottom")
		(5 "F.SilkS" user "Ref Des/Silkscreen Top")
		(7 "B.SilkS" user "Ref Des/Silkscreen Bottom")
		(1 "F.Mask" user "Board Geometry/Soldermask Top")
		(3 "B.Mask" user "Board Geometry/Soldermask Bottom")
		(17 "Dwgs.User" user "User.Drawings")
		(19 "Cmts.User" user "User.Comments")
		(21 "Eco1.User" user "User.Eco1")
		(23 "Eco2.User" user "User.Eco2")
		(25 "Edge.Cuts" user "Board Geometry/Outline")
		(27 "Margin" user)
		(31 "F.CrtYd" user "Package Geometry/Place Bound Top")
		(29 "B.CrtYd" user "Package Geometry/Place Bound Bottom")
		(35 "F.Fab" user "Ref Des/Assembly Top")
		(33 "B.Fab" user "Ref Des/Assembly Bottom")
	)
	(footprint ""
		(layer "F.Cu")
		(at 285.242762 -14.36243)
		(property "Reference" "R4214"
			(at 0 0 0)
			(layer "F.SilkS")
			(hide yes)
			(effects
				(font
					(size 1.27 1.27)
				)
			)
		)
		(property "Value" ""
			(at 0 0 0)
			(layer "F.Fab")
			(effects
				(font
					(size 1.27 1.27)
				)
			)
		)
		(duplicate_pad_numbers_are_jumpers no)
		(fp_line
			(start -0.7874 -0.4064)
			(end 0.7874 -0.4064)
			(stroke
				(width 0.1524)
				(type default)
			)
			(layer "F.SilkS")
		)
		(fp_line
			(start -0.7874 0.4064)
			(end -0.7874 -0.4064)
			(stroke
				(width 0.1524)
				(type default)
			)
			(layer "F.SilkS")
		)
		(fp_line
			(start 0.7874 -0.4064)
			(end 0.7874 0.4064)
			(stroke
				(width 0.1524)
				(type default)
			)
			(layer "F.SilkS")
		)
		(fp_line
			(start 0.7874 0.4064)
			(end -0.7874 0.4064)
			(stroke
				(width 0.1524)
				(type default)
			)
			(layer "F.SilkS")
		)
		(fp_line
			(start -0.67945 -0.305054)
			(end -0.12065 -0.305054)
			(stroke
				(width 0.1)
				(type default)
			)
			(layer "F.Fab")
		)
		(fp_line
			(start -0.67945 0.3048)
			(end -0.67945 -0.305054)
			(stroke
				(width 0.1)
				(type default)
			)
			(layer "F.Fab")
		)
		(fp_line
			(start -0.12065 -0.305054)
			(end -0.12065 -0.2794)
			(stroke
				(width 0.1)
				(type default)
			)
			(layer "F.Fab")
		)
		(fp_line
			(start -0.12065 -0.2794)
			(end 0.12065 -0.2794)
			(stroke
				(width 0.1)
				(type default)
			)
			(layer "F.Fab")
		)
		(fp_line
			(start -0.12065 0.2794)
			(end -0.12065 0.3048)
			(stroke
				(width 0.1)
				(type default)
			)
			(layer "F.Fab")
		)
		(fp_line
			(start -0.12065 0.3048)
			(end -0.67945 0.3048)
			(stroke
				(width 0.1)
				(type default)
			)
			(layer "F.Fab")
		)
		(fp_line
			(start 0.120396 0.2794)
			(end -0.12065 0.2794)
			(stroke
				(width 0.1)
				(type default)
			)
			(layer "F.Fab")
		)
		(fp_line
			(start 0.120396 0.3048)
			(end 0.120396 0.2794)
			(stroke
				(width 0.1)
				(type default)
			)
			(layer "F.Fab")
		)
		(fp_line
			(start 0.12065 -0.3048)
			(end 0.67945 -0.3048)
			(stroke
				(width 0.1)
				(type default)
			)
			(layer "F.Fab")
		)
		(fp_line
			(start 0.12065 -0.2794)
			(end 0.12065 -0.3048)
			(stroke
				(width 0.1)
				(type default)
			)
			(layer "F.Fab")
		)
		(fp_line
			(start 0.67945 -0.3048)
			(end 0.67945 0.3048)
			(stroke
				(width 0.1)
				(type default)
			)
			(layer "F.Fab")
		)
		(fp_line
			(start 0.67945 0.3048)
			(end 0.120396 0.3048)
			(stroke
				(width 0.1)
				(type default)
			)
			(layer "F.Fab")
		)
		(pad "1" smd circle
			(at -0.40005 0)
			(size 0 0)
			(layers "F.Cu" "F.Mask" "F.Paste")
			(net "FM_THERMAL_ALERT_N")
		)
		(pad "2" smd circle
			(at 0.40005 0)
			(size 0 0)
			(layers "F.Cu" "F.Mask" "F.Paste")
			(net "FM_G751_1_ALERT_N")
		)
	)
	(footprint ""
		(layer "F.Cu")
		(at 153.825194 -402.371052 -90)
		(property "Reference" "C765"
			(at 0 0 270)
			(layer "F.SilkS")
			(hide yes)
			(effects
				(font
					(size 1.27 1.27)
				)
			)
		)
		(property "Value" ""
			(at 0 0 270)
			(layer "F.Fab")
			(effects
				(font
					(size 1.27 1.27)
				)
			)
		)
		(duplicate_pad_numbers_are_jumpers no)
		(fp_line
			(start -0.299974 0.150114)
			(end -0.299974 -0.150114)
			(stroke
				(width 0.1)
				(type default)
			)
			(layer "F.Fab")
		)
		(fp_line
			(start 0.299974 0.150114)
			(end -0.299974 0.150114)
			(stroke
				(width 0.1)
				(type default)
			)
			(layer "F.Fab")
		)
		(fp_line
			(start -0.299974 -0.150114)
			(end 0.299974 -0.150114)
			(stroke
				(width 0.1)
				(type default)
			)
			(layer "F.Fab")
		)
		(fp_line
			(start 0.299974 -0.150114)
			(end 0.299974 0.150114)
			(stroke
				(width 0.1)
				(type default)
			)
			(layer "F.Fab")
		)
		(pad "1" smd rect
			(at -0.2667 0 270)
			(size 0.3048 0.381)
			(layers "F.Cu" "F.Mask" "F.Paste")
			(net "P5E_CPU1_PE2_TX_C_DP<4>")
		)
		(pad "2" smd rect
			(at 0.2667 0 270)
			(size 0.3048 0.381)
			(layers "F.Cu" "F.Mask" "F.Paste")
			(net "P5E_CPU1_PE2_TX_DP<4>")
		)
	)
	(footprint ""
		(layer "F.Cu")
		(at 205.397608 -406.855422)
		(property "Reference" "PR3920"
			(at 0 0 0)
			(layer "F.SilkS")
			(hide yes)
			(effects
				(font
					(size 1.27 1.27)
				)
			)
		)
		(property "Value" ""
			(at 0 0 0)
			(layer "F.Fab")
			(effects
				(font
					(size 1.27 1.27)
				)
			)
		)
		(duplicate_pad_numbers_are_jumpers no)
		(fp_line
			(start -0.7874 -0.4064)
			(end 0.7874 -0.4064)
			(stroke
				(width 0.1524)
				(type default)
			)
			(layer "F.SilkS")
		)
		(fp_line
			(start -0.7874 0.4064)
			(end -0.7874 -0.4064)
			(stroke
				(width 0.1524)
				(type default)
			)
			(layer "F.SilkS")
		)
		(fp_line
			(start 0.7874 -0.4064)
			(end 0.7874 0.4064)
			(stroke
				(width 0.1524)
				(type default)
			)
			(layer "F.SilkS")
		)
		(fp_line
			(start 0.7874 0.4064)
			(end -0.7874 0.4064)
			(stroke
				(width 0.1524)
				(type default)
			)
			(layer "F.SilkS")
		)
		(fp_line
			(start -0.67945 -0.305054)
			(end -0.12065 -0.305054)
			(stroke
				(width 0.1)
				(type default)
			)
			(layer "F.Fab")
		)
		(fp_line
			(start -0.67945 0.3048)
			(end -0.67945 -0.305054)
			(stroke
				(width 0.1)
				(type default)
			)
			(layer "F.Fab")
		)
		(fp_line
			(start -0.12065 -0.305054)
			(end -0.12065 -0.2794)
			(stroke
				(width 0.1)
				(type default)
			)
			(layer "F.Fab")
		)
		(fp_line
			(start -0.12065 -0.2794)
			(end 0.12065 -0.2794)
			(stroke
				(width 0.1)
				(type default)
			)
			(layer "F.Fab")
		)
		(fp_line
			(start -0.12065 0.2794)
			(end -0.12065 0.3048)
			(stroke
				(width 0.1)
				(type default)
			)
			(layer "F.Fab")
		)
		(fp_line
			(start -0.12065 0.3048)
			(end -0.67945 0.3048)
			(stroke
				(width 0.1)
				(type default)
			)
			(layer "F.Fab")
		)
		(fp_line
			(start 0.120396 0.2794)
			(end -0.12065 0.2794)
			(stroke
				(width 0.1)
				(type default)
			)
			(layer "F.Fab")
		)
		(fp_line
			(start 0.120396 0.3048)
			(end 0.120396 0.2794)
			(stroke
				(width 0.1)
				(type default)
			)
			(layer "F.Fab")
		)
		(fp_line
			(start 0.12065 -0.3048)
			(end 0.67945 -0.3048)
			(stroke
				(width 0.1)
				(type default)
			)
			(layer "F.Fab")
		)
		(fp_line
			(start 0.12065 -0.2794)
			(end 0.12065 -0.3048)
			(stroke
				(width 0.1)
				(type default)
			)
			(layer "F.Fab")
		)
		(fp_line
			(start 0.67945 -0.3048)
			(end 0.67945 0.3048)
			(stroke
				(width 0.1)
				(type default)
			)
			(layer "F.Fab")
		)
		(fp_line
			(start 0.67945 0.3048)
			(end 0.120396 0.3048)
			(stroke
				(width 0.1)
				(type default)
			)
			(layer "F.Fab")
		)
		(pad "1" smd circle
			(at -0.40005 0)
			(size 0 0)
			(layers "F.Cu" "F.Mask" "F.Paste")
			(net "HSC_FLT_TYPE_1")
		)
		(pad "2" smd circle
			(at 0.40005 0)
			(size 0 0)
			(layers "F.Cu" "F.Mask" "F.Paste")
			(net "HSC_FLT_TYPE")
		)
	)
	(footprint ""
		(layer "F.Cu")
		(at 374.00484 -339.602572 90)
		(property "Reference" "PC249"
			(at 0 0 90)
			(layer "F.SilkS")
			(hide yes)
			(effects
				(font
					(size 1.27 1.27)
				)
			)
		)
		(property "Value" ""
			(at 0 0 90)
			(layer "F.Fab")
			(effects
				(font
					(size 1.27 1.27)
				)
			)
		)
		(duplicate_pad_numbers_are_jumpers no)
		(fp_line
			(start 0.7874 -0.4064)
			(end 0.7874 0.4064)
			(stroke
				(width 0.1524)
				(type default)
			)
			(layer "F.SilkS")
		)
		(fp_line
			(start -0.7874 -0.4064)
			(end 0.7874 -0.4064)
			(stroke
				(width 0.1524)
				(type default)
			)
			(layer "F.SilkS")
		)
		(fp_line
			(start 0.7874 0.4064)
			(end -0.7874 0.4064)
			(stroke
				(width 0.1524)
				(type default)
			)
			(layer "F.SilkS")
		)
		(fp_line
			(start -0.7874 0.4064)
			(end -0.7874 -0.4064)
			(stroke
				(width 0.1524)
				(type default)
			)
			(layer "F.SilkS")
		)
		(fp_line
			(start -0.12065 -0.305054)
			(end -0.12065 -0.2794)
			(stroke
				(width 0.1)
				(type default)
			)
			(layer "F.Fab")
		)
		(fp_line
			(start -0.67945 -0.305054)
			(end -0.12065 -0.305054)
			(stroke
				(width 0.1)
				(type default)
			)
			(layer "F.Fab")
		)
		(fp_line
			(start 0.67945 -0.3048)
			(end 0.67945 0.3048)
			(stroke
				(width 0.1)
				(type default)
			)
			(layer "F.Fab")
		)
		(fp_line
			(start 0.12065 -0.3048)
			(end 0.67945 -0.3048)
			(stroke
				(width 0.1)
				(type default)
			)
			(layer "F.Fab")
		)
		(fp_line
			(start 0.12065 -0.2794)
			(end 0.12065 -0.3048)
			(stroke
				(width 0.1)
				(type default)
			)
			(layer "F.Fab")
		)
		(fp_line
			(start -0.12065 -0.2794)
			(end 0.12065 -0.2794)
			(stroke
				(width 0.1)
				(type default)
			)
			(layer "F.Fab")
		)
		(fp_line
			(start 0.120396 0.2794)
			(end -0.12065 0.2794)
			(stroke
				(width 0.1)
				(type default)
			)
			(layer "F.Fab")
		)
		(fp_line
			(start -0.12065 0.2794)
			(end -0.12065 0.3048)
			(stroke
				(width 0.1)
				(type default)
			)
			(layer "F.Fab")
		)
		(fp_line
			(start 0.67945 0.3048)
			(end 0.120396 0.3048)
			(stroke
				(width 0.1)
				(type default)
			)
			(layer "F.Fab")
		)
		(fp_line
			(start 0.120396 0.3048)
			(end 0.120396 0.2794)
			(stroke
				(width 0.1)
				(type default)
			)
			(layer "F.Fab")
		)
		(fp_line
			(start -0.12065 0.3048)
			(end -0.67945 0.3048)
			(stroke
				(width 0.1)
				(type default)
			)
			(layer "F.Fab")
		)
		(fp_line
			(start -0.67945 0.3048)
			(end -0.67945 -0.305054)
			(stroke
				(width 0.1)
				(type default)
			)
			(layer "F.Fab")
		)
		(pad "1" smd circle
			(at -0.40005 0 90)
			(size 0 0)
			(layers "F.Cu" "F.Mask" "F.Paste")
			(net "PVCCIN_CPU0_VDD5")
		)
		(pad "2" smd circle
			(at 0.40005 0 90)
			(size 0 0)
			(layers "F.Cu" "F.Mask" "F.Paste")
			(net "GND")
		)
	)
	(footprint ""
		(layer "F.Cu")
		(at 66.162174 -16.37157 180)
		(property "Reference" "C1831"
			(at 0 0 180)
			(layer "F.SilkS")
			(hide yes)
			(effects
				(font
					(size 1.27 1.27)
				)
			)
		)
		(property "Value" ""
			(at 0 0 180)
			(layer "F.Fab")
			(effects
				(font
					(size 1.27 1.27)
				)
			)
		)
		(duplicate_pad_numbers_are_jumpers no)
		(fp_line
			(start 0.7874 0.4064)
			(end -0.7874 0.4064)
			(stroke
				(width 0.1524)
				(type default)
			)
			(layer "F.SilkS")
		)
		(fp_line
			(start 0.7874 -0.4064)
			(end 0.7874 0.4064)
			(stroke
				(width 0.1524)
				(type default)
			)
			(layer "F.SilkS")
		)
		(fp_line
			(start -0.7874 0.4064)
			(end -0.7874 -0.4064)
			(stroke
				(width 0.1524)
				(type default)
			)
			(layer "F.SilkS")
		)
		(fp_line
			(start -0.7874 -0.4064)
			(end 0.7874 -0.4064)
			(stroke
				(width 0.1524)
				(type default)
			)
			(layer "F.SilkS")
		)
		(fp_line
			(start 0.67945 0.3048)
			(end 0.120396 0.3048)
			(stroke
				(width 0.1)
				(type default)
			)
			(layer "F.Fab")
		)
		(fp_line
			(start 0.67945 -0.3048)
			(end 0.67945 0.3048)
			(stroke
				(width 0.1)
				(type default)
			)
			(layer "F.Fab")
		)
		(fp_line
			(start 0.12065 -0.2794)
			(end 0.12065 -0.3048)
			(stroke
				(width 0.1)
				(type default)
			)
			(layer "F.Fab")
		)
		(fp_line
			(start 0.12065 -0.3048)
			(end 0.67945 -0.3048)
			(stroke
				(width 0.1)
				(type default)
			)
			(layer "F.Fab")
		)
		(fp_line
			(start 0.120396 0.3048)
			(end 0.120396 0.2794)
			(stroke
				(width 0.1)
				(type default)
			)
			(layer "F.Fab")
		)
		(fp_line
			(start 0.120396 0.2794)
			(end -0.12065 0.2794)
			(stroke
				(width 0.1)
				(type default)
			)
			(layer "F.Fab")
		)
		(fp_line
			(start -0.12065 0.3048)
			(end -0.67945 0.3048)
			(stroke
				(width 0.1)
				(type default)
			)
			(layer "F.Fab")
		)
		(fp_line
			(start -0.12065 0.2794)
			(end -0.12065 0.3048)
			(stroke
				(width 0.1)
				(type default)
			)
			(layer "F.Fab")
		)
		(fp_line
			(start -0.12065 -0.2794)
			(end 0.12065 -0.2794)
			(stroke
				(width 0.1)
				(type default)
			)
			(layer "F.Fab")
		)
		(fp_line
			(start -0.12065 -0.305054)
			(end -0.12065 -0.2794)
			(stroke
				(width 0.1)
				(type default)
			)
			(layer "F.Fab")
		)
		(fp_line
			(start -0.67945 0.3048)
			(end -0.67945 -0.305054)
			(stroke
				(width 0.1)
				(type default)
			)
			(layer "F.Fab")
		)
		(fp_line
			(start -0.67945 -0.305054)
			(end -0.12065 -0.305054)
			(stroke
				(width 0.1)
				(type default)
			)
			(layer "F.Fab")
		)
		(pad "1" smd circle
			(at -0.40005 0 180)
			(size 0 0)
			(layers "F.Cu" "F.Mask" "F.Paste")
			(net "P12V_OCP_V3_2")
		)
		(pad "2" smd circle
			(at 0.40005 0 180)
			(size 0 0)
			(layers "F.Cu" "F.Mask" "F.Paste")
			(net "GND")
		)
	)
	(footprint ""
		(layer "F.Cu")
		(at 66.86296 -61.158628 90)
		(property "Reference" "PC1321"
			(at 0 0 90)
			(layer "F.SilkS")
			(hide yes)
			(effects
				(font
					(size 1.27 1.27)
				)
			)
		)
		(property "Value" ""
			(at 0 0 90)
			(layer "F.Fab")
			(effects
				(font
					(size 1.27 1.27)
				)
			)
		)
		(duplicate_pad_numbers_are_jumpers no)
		(fp_line
			(start 0.7874 -0.4064)
			(end 0.7874 0.4064)
			(stroke
				(width 0.1524)
				(type default)
			)
			(layer "F.SilkS")
		)
		(fp_line
			(start -0.7874 -0.4064)
			(end 0.7874 -0.4064)
			(stroke
				(width 0.1524)
				(type default)
			)
			(layer "F.SilkS")
		)
		(fp_line
			(start 0.7874 0.4064)
			(end -0.7874 0.4064)
			(stroke
				(width 0.1524)
				(type default)
			)
			(layer "F.SilkS")
		)
		(fp_line
			(start -0.7874 0.4064)
			(end -0.7874 -0.4064)
			(stroke
				(width 0.1524)
				(type default)
			)
			(layer "F.SilkS")
		)
		(fp_line
			(start -0.12065 -0.305054)
			(end -0.12065 -0.2794)
			(stroke
				(width 0.1)
				(type default)
			)
			(layer "F.Fab")
		)
		(fp_line
			(start -0.67945 -0.305054)
			(end -0.12065 -0.305054)
			(stroke
				(width 0.1)
				(type default)
			)
			(layer "F.Fab")
		)
		(fp_line
			(start 0.67945 -0.3048)
			(end 0.67945 0.3048)
			(stroke
				(width 0.1)
				(type default)
			)
			(layer "F.Fab")
		)
		(fp_line
			(start 0.12065 -0.3048)
			(end 0.67945 -0.3048)
			(stroke
				(width 0.1)
				(type default)
			)
			(layer "F.Fab")
		)
		(fp_line
			(start 0.12065 -0.2794)
			(end 0.12065 -0.3048)
			(stroke
				(width 0.1)
				(type default)
			)
			(layer "F.Fab")
		)
		(fp_line
			(start -0.12065 -0.2794)
			(end 0.12065 -0.2794)
			(stroke
				(width 0.1)
				(type default)
			)
			(layer "F.Fab")
		)
		(fp_line
			(start 0.120396 0.2794)
			(end -0.12065 0.2794)
			(stroke
				(width 0.1)
				(type default)
			)
			(layer "F.Fab")
		)
		(fp_line
			(start -0.12065 0.2794)
			(end -0.12065 0.3048)
			(stroke
				(width 0.1)
				(type default)
			)
			(layer "F.Fab")
		)
		(fp_line
			(start 0.67945 0.3048)
			(end 0.120396 0.3048)
			(stroke
				(width 0.1)
				(type default)
			)
			(layer "F.Fab")
		)
		(fp_line
			(start 0.120396 0.3048)
			(end 0.120396 0.2794)
			(stroke
				(width 0.1)
				(type default)
			)
			(layer "F.Fab")
		)
		(fp_line
			(start -0.12065 0.3048)
			(end -0.67945 0.3048)
			(stroke
				(width 0.1)
				(type default)
			)
			(layer "F.Fab")
		)
		(fp_line
			(start -0.67945 0.3048)
			(end -0.67945 -0.305054)
			(stroke
				(width 0.1)
				(type default)
			)
			(layer "F.Fab")
		)
		(pad "1" smd circle
			(at -0.40005 0 90)
			(size 0 0)
			(layers "F.Cu" "F.Mask" "F.Paste")
			(net "P3V3_OCP_DVDT_2")
		)
		(pad "2" smd circle
			(at 0.40005 0 90)
			(size 0 0)
			(layers "F.Cu" "F.Mask" "F.Paste")
			(net "GND")
		)
	)
)
